(kicad_pcb
	(version 20260206)
	(generator "pcbnew")
	(generator_version "10.0")
	(general
		(thickness 1.6)
		(legacy_teardrops no)
	)
	(paper "A4")
	(title_block
		(title "peb — Lightning_PEB_BRD.brd")
		(comment 1 "Lightning (Wiwynn / Facebook NVMe JBOF) / footprints 1972-1979 of 2563")
	)
	(layers
		(0 "F.Cu" signal "TOP")
		(4 "In1.Cu" signal "L2GND")
		(6 "In2.Cu" signal "L3")
		(8 "In3.Cu" signal "L4VCC")
		(10 "In4.Cu" signal "L5VCC")
		(12 "In5.Cu" signal "L6")
		(14 "In6.Cu" signal "L7GND")
		(2 "B.Cu" signal "BOTTOM")
		(9 "F.Adhes" user "F.Adhesive")
		(11 "B.Adhes" user "B.Adhesive")
		(13 "F.Paste" user "Package Geometry/Pastemask Top")
		(15 "B.Paste" user "Package Geometry/Pastemask Bottom")
		(5 "F.SilkS" user "Ref Des/Silkscreen Top")
		(7 "B.SilkS" user "Ref Des/Silkscreen Bottom")
		(1 "F.Mask" user "Board Geometry/Soldermask Top")
		(3 "B.Mask" user "Board Geometry/Soldermask Bottom")
		(17 "Dwgs.User" user "User.Drawings")
		(19 "Cmts.User" user "User.Comments")
		(21 "Eco1.User" user "User.Eco1")
		(23 "Eco2.User" user "User.Eco2")
		(25 "Edge.Cuts" user "Board Geometry/Outline")
		(27 "Margin" user)
		(31 "F.CrtYd" user "Package Geometry/Place Bound Top")
		(29 "B.CrtYd" user "Package Geometry/Place Bound Bottom")
		(35 "F.Fab" user "Ref Des/Assembly Top")
		(33 "B.Fab" user "Ref Des/Assembly Bottom")
	)
	(footprint ""
		(layer "B.Cu")
		(at 252.603 -53.001672 -90)
		(property "Reference" "C582"
			(at 0 0 90)
			(layer "B.SilkS")
			(hide yes)
			(effects
				(font
					(size 1.27 1.27)
				)
				(justify mirror)
			)
		)
		(property "Value" "SCD1U16V1KX-1-GP"
			(at 2.8321 -1.7399 270)
			(unlocked yes)
			(layer "B.Fab")
			(hide yes)
			(effects
				(font
					(size 1.016 1.016)
					(thickness 0.1524)
				)
				(justify mirror)
			)
		)
		(property "Device Type" "C0201H13"
			(at 2.8321 -3.2639 270)
			(unlocked yes)
			(layer "B.Fab")
			(hide yes)
			(effects
				(font
					(size 1.016 1.016)
					(thickness 0.1524)
				)
				(justify mirror)
			)
		)
		(duplicate_pad_numbers_are_jumpers no)
		(fp_rect
			(start 0.2794 0.6477)
			(end -0.2794 -0.6477)
			(stroke
				(width 0)
				(type default)
			)
			(fill no)
			(layer "B.CrtYd")
		)
		(fp_rect
			(start 0.2794 0.6477)
			(end -0.2794 -0.6477)
			(stroke
				(width 0)
				(type default)
			)
			(fill no)
			(layer "B.Fab")
		)
		(pad "1" smd custom
			(at 0 -0.2794 90)
			(size 0.0762 0.0762)
			(layers "B.Cu" "B.Mask" "B.Paste")
			(net "DUT_AVD_PCIE")
			(options
				(clearance outline)
				(anchor circle)
			)
			(primitives
				(gr_poly
					(pts
						(arc
							(start 0.1524 0.127)
							(mid 0.137521 0.162921)
							(end 0.1016 0.1778)
						)
						(arc
							(start -0.1016 0.1778)
							(mid -0.137521 0.162921)
							(end -0.1524 0.127)
						)
						(arc
							(start -0.1524 -0.127)
							(mid -0.137521 -0.162921)
							(end -0.1016 -0.1778)
						)
						(arc
							(start 0.1016 -0.1778)
							(mid 0.137521 -0.162921)
							(end 0.1524 -0.127)
						)
					)
					(width 0)
					(fill yes)
				)
			)
		)
		(pad "2" smd custom
			(at 0 0.2794 90)
			(size 0.0762 0.0762)
			(layers "B.Cu" "B.Mask" "B.Paste")
			(net "GND")
			(options
				(clearance outline)
				(anchor circle)
			)
			(primitives
				(gr_poly
					(pts
						(arc
							(start 0.1524 0.127)
							(mid 0.137521 0.162921)
							(end 0.1016 0.1778)
						)
						(arc
							(start -0.1016 0.1778)
							(mid -0.137521 0.162921)
							(end -0.1524 0.127)
						)
						(arc
							(start -0.1524 -0.127)
							(mid -0.137521 -0.162921)
							(end -0.1016 -0.1778)
						)
						(arc
							(start 0.1016 -0.1778)
							(mid 0.137521 -0.162921)
							(end 0.1524 -0.127)
						)
					)
					(width 0)
					(fill yes)
				)
			)
		)
	)
	(footprint ""
		(layer "B.Cu")
		(at 254.7874 -26.1112 180)
		(property "Reference" "R772"
			(at 0 0 0)
			(layer "B.SilkS")
			(hide yes)
			(effects
				(font
					(size 1.27 1.27)
				)
				(justify mirror)
			)
		)
		(property "Value" "3K3R2F-2-GP"
			(at -0.064008 -3.993896 180)
			(unlocked yes)
			(layer "B.Fab")
			(hide yes)
			(effects
				(font
					(size 1.016 1.016)
					(thickness 0.1524)
				)
				(justify mirror)
			)
		)
		(property "Device Type" "R402H16"
			(at -0.064008 -5.517896 180)
			(unlocked yes)
			(layer "B.Fab")
			(hide yes)
			(effects
				(font
					(size 1.016 1.016)
					(thickness 0.1524)
				)
				(justify mirror)
			)
		)
		(duplicate_pad_numbers_are_jumpers no)
		(fp_line
			(start 0.508 -0.9398)
			(end 0.508 0.9398)
			(stroke
				(width 0.1524)
				(type default)
			)
			(layer "B.SilkS")
		)
		(fp_line
			(start -0.508 -0.9398)
			(end 0.508 -0.9398)
			(stroke
				(width 0.1524)
				(type default)
			)
			(layer "B.SilkS")
		)
		(fp_rect
			(start 0.508 0.9398)
			(end -0.508 -0.9398)
			(stroke
				(width 0)
				(type default)
			)
			(fill no)
			(layer "B.CrtYd")
		)
		(fp_rect
			(start 0.508 0.9398)
			(end -0.508 -0.9398)
			(stroke
				(width 0)
				(type default)
			)
			(fill no)
			(layer "B.Fab")
		)
		(pad "1" smd custom
			(at 0 -0.4445)
			(size 0.1397 0.1397)
			(layers "B.Cu" "B.Mask" "B.Paste")
			(net "P3V3_GPIO")
			(options
				(clearance outline)
				(anchor circle)
			)
			(primitives
				(gr_poly
					(pts
						(arc
							(start -0.1778 0.2794)
							(mid -0.249642 0.249642)
							(end -0.2794 0.1778)
						)
						(arc
							(start -0.2794 -0.1778)
							(mid -0.249642 -0.249642)
							(end -0.1778 -0.2794)
						)
						(arc
							(start 0.1778 -0.2794)
							(mid 0.249642 -0.249642)
							(end 0.2794 -0.1778)
						)
						(arc
							(start 0.2794 0.1778)
							(mid 0.249642 0.249642)
							(end 0.1778 0.2794)
						)
					)
					(width 0)
					(fill yes)
				)
			)
		)
		(pad "2" smd custom
			(at 0 0.4445)
			(size 0.1397 0.1397)
			(layers "B.Cu" "B.Mask" "B.Paste")
			(net "TWI_SCL0")
			(options
				(clearance outline)
				(anchor circle)
			)
			(primitives
				(gr_poly
					(pts
						(arc
							(start -0.1778 0.2794)
							(mid -0.249642 0.249642)
							(end -0.2794 0.1778)
						)
						(arc
							(start -0.2794 -0.1778)
							(mid -0.249642 -0.249642)
							(end -0.1778 -0.2794)
						)
						(arc
							(start 0.1778 -0.2794)
							(mid 0.249642 -0.249642)
							(end 0.2794 -0.1778)
						)
						(arc
							(start 0.2794 0.1778)
							(mid 0.249642 0.249642)
							(end 0.1778 0.2794)
						)
					)
					(width 0)
					(fill yes)
				)
			)
		)
	)
	(footprint ""
		(layer "B.Cu")
		(at 123.698 -199.7456)
		(property "Reference" "C3209"
			(at 0 0 0)
			(layer "B.SilkS")
			(hide yes)
			(effects
				(font
					(size 1.27 1.27)
				)
				(justify mirror)
			)
		)
		(property "Value" "SCD1U25V2KX-2-GP"
			(at -1.1811 -2.7051 0)
			(unlocked yes)
			(layer "B.Fab")
			(hide yes)
			(effects
				(font
					(size 1.016 1.016)
					(thickness 0.1524)
				)
				(justify mirror)
			)
		)
		(property "Device Type" "C402H22"
			(at -1.1811 -4.2291 0)
			(unlocked yes)
			(layer "B.Fab")
			(hide yes)
			(effects
				(font
					(size 1.016 1.016)
					(thickness 0.1524)
				)
				(justify mirror)
			)
		)
		(duplicate_pad_numbers_are_jumpers no)
		(fp_rect
			(start 0.4318 0.9525)
			(end -0.4318 -0.9525)
			(stroke
				(width 0)
				(type default)
			)
			(fill no)
			(layer "B.CrtYd")
		)
		(fp_rect
			(start 0.4318 0.9525)
			(end -0.4318 -0.9525)
			(stroke
				(width 0)
				(type default)
			)
			(fill no)
			(layer "B.Fab")
		)
		(pad "1" smd custom
			(at 0 -0.4445 180)
			(size 0.1524 0.1524)
			(layers "B.Cu" "B.Mask" "B.Paste")
			(net "P3V3_STBY")
			(options
				(clearance outline)
				(anchor circle)
			)
			(primitives
				(gr_poly
					(pts
						(arc
							(start 0.3048 0.2032)
							(mid 0.275042 0.275042)
							(end 0.2032 0.3048)
						)
						(arc
							(start -0.2032 0.3048)
							(mid -0.275042 0.275042)
							(end -0.3048 0.2032)
						)
						(arc
							(start -0.3048 -0.2032)
							(mid -0.275042 -0.275042)
							(end -0.2032 -0.3048)
						)
						(arc
							(start 0.2032 -0.3048)
							(mid 0.275042 -0.275042)
							(end 0.3048 -0.2032)
						)
					)
					(width 0)
					(fill yes)
				)
			)
		)
		(pad "2" smd custom
			(at 0 0.4445 180)
			(size 0.1524 0.1524)
			(layers "B.Cu" "B.Mask" "B.Paste")
			(net "GND")
			(options
				(clearance outline)
				(anchor circle)
			)
			(primitives
				(gr_poly
					(pts
						(arc
							(start 0.3048 0.2032)
							(mid 0.275042 0.275042)
							(end 0.2032 0.3048)
						)
						(arc
							(start -0.2032 0.3048)
							(mid -0.275042 0.275042)
							(end -0.3048 0.2032)
						)
						(arc
							(start -0.3048 -0.2032)
							(mid -0.275042 -0.275042)
							(end -0.2032 -0.3048)
						)
						(arc
							(start 0.2032 -0.3048)
							(mid 0.275042 -0.275042)
							(end 0.3048 -0.2032)
						)
					)
					(width 0)
					(fill yes)
				)
			)
		)
	)
	(footprint ""
		(layer "B.Cu")
		(at 46.863 -138.938)
		(property "Reference" "R308"
			(at 0 0 0)
			(layer "B.SilkS")
			(hide yes)
			(effects
				(font
					(size 1.27 1.27)
				)
				(justify mirror)
			)
		)
		(property "Value" "0R2J-2-GP"
			(at -0.064008 -3.993896 0)
			(unlocked yes)
			(layer "B.Fab")
			(hide yes)
			(effects
				(font
					(size 1.016 1.016)
					(thickness 0.1524)
				)
				(justify mirror)
			)
		)
		(property "Device Type" "R402H16"
			(at -0.064008 -5.517896 0)
			(unlocked yes)
			(layer "B.Fab")
			(hide yes)
			(effects
				(font
					(size 1.016 1.016)
					(thickness 0.1524)
				)
				(justify mirror)
			)
		)
		(duplicate_pad_numbers_are_jumpers no)
		(fp_line
			(start -0.508 -0.9398)
			(end 0.508 -0.9398)
			(stroke
				(width 0.1524)
				(type default)
			)
			(layer "B.SilkS")
		)
		(fp_line
			(start 0.508 -0.9398)
			(end 0.508 0.9398)
			(stroke
				(width 0.1524)
				(type default)
			)
			(layer "B.SilkS")
		)
		(fp_rect
			(start 0.508 0.9398)
			(end -0.508 -0.9398)
			(stroke
				(width 0)
				(type default)
			)
			(fill no)
			(layer "B.CrtYd")
		)
		(fp_rect
			(start 0.508 0.9398)
			(end -0.508 -0.9398)
			(stroke
				(width 0)
				(type default)
			)
			(fill no)
			(layer "B.Fab")
		)
		(pad "1" smd custom
			(at 0 -0.4445 180)
			(size 0.1397 0.1397)
			(layers "B.Cu" "B.Mask" "B.Paste")
			(net "PWM_EXP_A")
			(options
				(clearance outline)
				(anchor circle)
			)
			(primitives
				(gr_poly
					(pts
						(arc
							(start -0.1778 0.2794)
							(mid -0.249642 0.249642)
							(end -0.2794 0.1778)
						)
						(arc
							(start -0.2794 -0.1778)
							(mid -0.249642 -0.249642)
							(end -0.1778 -0.2794)
						)
						(arc
							(start 0.1778 -0.2794)
							(mid 0.249642 -0.249642)
							(end 0.2794 -0.1778)
						)
						(arc
							(start 0.2794 0.1778)
							(mid 0.249642 0.249642)
							(end 0.1778 0.2794)
						)
					)
					(width 0)
					(fill yes)
				)
			)
		)
		(pad "2" smd custom
			(at 0 0.4445 180)
			(size 0.1397 0.1397)
			(layers "B.Cu" "B.Mask" "B.Paste")
			(net "FAN_PWM_PCIE_BMC")
			(options
				(clearance outline)
				(anchor circle)
			)
			(primitives
				(gr_poly
					(pts
						(arc
							(start -0.1778 0.2794)
							(mid -0.249642 0.249642)
							(end -0.2794 0.1778)
						)
						(arc
							(start -0.2794 -0.1778)
							(mid -0.249642 -0.249642)
							(end -0.1778 -0.2794)
						)
						(arc
							(start 0.1778 -0.2794)
							(mid 0.249642 -0.249642)
							(end 0.2794 -0.1778)
						)
						(arc
							(start 0.2794 0.1778)
							(mid 0.249642 0.249642)
							(end 0.1778 0.2794)
						)
					)
					(width 0)
					(fill yes)
				)
			)
		)
	)
	(footprint ""
		(layer "B.Cu")
		(at 167.513 -33.528)
		(property "Reference" "R2930"
			(at 0 0 0)
			(layer "B.SilkS")
			(hide yes)
			(effects
				(font
					(size 1.27 1.27)
				)
				(justify mirror)
			)
		)
		(property "Value" "0R2J-2-GP"
			(at -0.064008 -3.993896 0)
			(unlocked yes)
			(layer "B.Fab")
			(hide yes)
			(effects
				(font
					(size 1.016 1.016)
					(thickness 0.1524)
				)
				(justify mirror)
			)
		)
		(property "Device Type" "R402H16"
			(at -0.064008 -5.517896 0)
			(unlocked yes)
			(layer "B.Fab")
			(hide yes)
			(effects
				(font
					(size 1.016 1.016)
					(thickness 0.1524)
				)
				(justify mirror)
			)
		)
		(duplicate_pad_numbers_are_jumpers no)
		(fp_line
			(start -0.508 -0.9398)
			(end 0.508 -0.9398)
			(stroke
				(width 0.1524)
				(type default)
			)
			(layer "B.SilkS")
		)
		(fp_line
			(start 0.508 -0.9398)
			(end 0.508 0.9398)
			(stroke
				(width 0.1524)
				(type default)
			)
			(layer "B.SilkS")
		)
		(fp_rect
			(start 0.508 0.9398)
			(end -0.508 -0.9398)
			(stroke
				(width 0)
				(type default)
			)
			(fill no)
			(layer "B.CrtYd")
		)
		(fp_rect
			(start 0.508 0.9398)
			(end -0.508 -0.9398)
			(stroke
				(width 0)
				(type default)
			)
			(fill no)
			(layer "B.Fab")
		)
		(pad "1" smd custom
			(at 0 -0.4445 180)
			(size 0.1397 0.1397)
			(layers "B.Cu" "B.Mask" "B.Paste")
			(net "BMC_I2C4_MINI4_SDA")
			(options
				(clearance outline)
				(anchor circle)
			)
			(primitives
				(gr_poly
					(pts
						(arc
							(start -0.1778 0.2794)
							(mid -0.249642 0.249642)
							(end -0.2794 0.1778)
						)
						(arc
							(start -0.2794 -0.1778)
							(mid -0.249642 -0.249642)
							(end -0.1778 -0.2794)
						)
						(arc
							(start 0.1778 -0.2794)
							(mid 0.249642 -0.249642)
							(end 0.2794 -0.1778)
						)
						(arc
							(start 0.2794 0.1778)
							(mid 0.249642 0.249642)
							(end 0.1778 0.2794)
						)
					)
					(width 0)
					(fill yes)
				)
			)
		)
		(pad "2" smd custom
			(at 0 0.4445 180)
			(size 0.1397 0.1397)
			(layers "B.Cu" "B.Mask" "B.Paste")
			(net "8644_CBL_PRSNT_R_4")
			(options
				(clearance outline)
				(anchor circle)
			)
			(primitives
				(gr_poly
					(pts
						(arc
							(start -0.1778 0.2794)
							(mid -0.249642 0.249642)
							(end -0.2794 0.1778)
						)
						(arc
							(start -0.2794 -0.1778)
							(mid -0.249642 -0.249642)
							(end -0.1778 -0.2794)
						)
						(arc
							(start 0.1778 -0.2794)
							(mid 0.249642 -0.249642)
							(end 0.2794 -0.1778)
						)
						(arc
							(start 0.2794 0.1778)
							(mid 0.249642 0.249642)
							(end 0.1778 0.2794)
						)
					)
					(width 0)
					(fill yes)
				)
			)
		)
	)
	(footprint ""
		(layer "B.Cu")
		(at 35.564064 -131.34848 90)
		(property "Reference" "C210"
			(at 0 0 90)
			(layer "B.SilkS")
			(hide yes)
			(effects
				(font
					(size 1.27 1.27)
				)
				(justify mirror)
			)
		)
		(property "Value" "SC1U10V2KX-4-GP"
			(at -1.1811 -2.7051 90)
			(unlocked yes)
			(layer "B.Fab")
			(hide yes)
			(effects
				(font
					(size 1.016 1.016)
					(thickness 0.1524)
				)
				(justify mirror)
			)
		)
		(property "Device Type" "C402H22"
			(at -1.1811 -4.2291 90)
			(unlocked yes)
			(layer "B.Fab")
			(hide yes)
			(effects
				(font
					(size 1.016 1.016)
					(thickness 0.1524)
				)
				(justify mirror)
			)
		)
		(duplicate_pad_numbers_are_jumpers no)
		(fp_rect
			(start 0.4318 0.9525)
			(end -0.4318 -0.9525)
			(stroke
				(width 0)
				(type default)
			)
			(fill no)
			(layer "B.CrtYd")
		)
		(fp_rect
			(start 0.4318 0.9525)
			(end -0.4318 -0.9525)
			(stroke
				(width 0)
				(type default)
			)
			(fill no)
			(layer "B.Fab")
		)
		(pad "1" smd custom
			(at 0 -0.4445 270)
			(size 0.1524 0.1524)
			(layers "B.Cu" "B.Mask" "B.Paste")
			(net "P3V3_STBY")
			(options
				(clearance outline)
				(anchor circle)
			)
			(primitives
				(gr_poly
					(pts
						(arc
							(start 0.3048 0.2032)
							(mid 0.275042 0.275042)
							(end 0.2032 0.3048)
						)
						(arc
							(start -0.2032 0.3048)
							(mid -0.275042 0.275042)
							(end -0.3048 0.2032)
						)
						(arc
							(start -0.3048 -0.2032)
							(mid -0.275042 -0.275042)
							(end -0.2032 -0.3048)
						)
						(arc
							(start 0.2032 -0.3048)
							(mid 0.275042 -0.275042)
							(end 0.3048 -0.2032)
						)
					)
					(width 0)
					(fill yes)
				)
			)
		)
		(pad "2" smd custom
			(at 0 0.4445 270)
			(size 0.1524 0.1524)
			(layers "B.Cu" "B.Mask" "B.Paste")
			(net "GND")
			(options
				(clearance outline)
				(anchor circle)
			)
			(primitives
				(gr_poly
					(pts
						(arc
							(start 0.3048 0.2032)
							(mid 0.275042 0.275042)
							(end 0.2032 0.3048)
						)
						(arc
							(start -0.2032 0.3048)
							(mid -0.275042 0.275042)
							(end -0.3048 0.2032)
						)
						(arc
							(start -0.3048 -0.2032)
							(mid -0.275042 -0.275042)
							(end -0.2032 -0.3048)
						)
						(arc
							(start 0.2032 -0.3048)
							(mid 0.275042 -0.275042)
							(end 0.3048 -0.2032)
						)
					)
					(width 0)
					(fill yes)
				)
			)
		)
	)
	(footprint ""
		(layer "B.Cu")
		(at 329.692 -180.086)
		(property "Reference" "R3214"
			(at 0 0 0)
			(layer "B.SilkS")
			(hide yes)
			(effects
				(font
					(size 1.27 1.27)
				)
				(justify mirror)
			)
		)
		(property "Value" "0R2J-2-GP"
			(at -0.064008 -3.993896 0)
			(unlocked yes)
			(layer "B.Fab")
			(hide yes)
			(effects
				(font
					(size 1.016 1.016)
					(thickness 0.1524)
				)
				(justify mirror)
			)
		)
		(property "Device Type" "R402H16"
			(at -0.064008 -5.517896 0)
			(unlocked yes)
			(layer "B.Fab")
			(hide yes)
			(effects
				(font
					(size 1.016 1.016)
					(thickness 0.1524)
				)
				(justify mirror)
			)
		)
		(duplicate_pad_numbers_are_jumpers no)
		(fp_line
			(start -0.508 -0.9398)
			(end 0.508 -0.9398)
			(stroke
				(width 0.1524)
				(type default)
			)
			(layer "B.SilkS")
		)
		(fp_line
			(start 0.508 -0.9398)
			(end 0.508 0.9398)
			(stroke
				(width 0.1524)
				(type default)
			)
			(layer "B.SilkS")
		)
		(fp_rect
			(start 0.508 0.9398)
			(end -0.508 -0.9398)
			(stroke
				(width 0)
				(type default)
			)
			(fill no)
			(layer "B.CrtYd")
		)
		(fp_rect
			(start 0.508 0.9398)
			(end -0.508 -0.9398)
			(stroke
				(width 0)
				(type default)
			)
			(fill no)
			(layer "B.Fab")
		)
		(pad "1" smd custom
			(at 0 -0.4445 180)
			(size 0.1397 0.1397)
			(layers "B.Cu" "B.Mask" "B.Paste")
			(net "BMC_SSD_RST#4")
			(options
				(clearance outline)
				(anchor circle)
			)
			(primitives
				(gr_poly
					(pts
						(arc
							(start -0.1778 0.2794)
							(mid -0.249642 0.249642)
							(end -0.2794 0.1778)
						)
						(arc
							(start -0.2794 -0.1778)
							(mid -0.249642 -0.249642)
							(end -0.1778 -0.2794)
						)
						(arc
							(start 0.1778 -0.2794)
							(mid 0.249642 -0.249642)
							(end 0.2794 -0.1778)
						)
						(arc
							(start 0.2794 0.1778)
							(mid 0.249642 0.249642)
							(end 0.1778 0.2794)
						)
					)
					(width 0)
					(fill yes)
				)
			)
		)
		(pad "2" smd custom
			(at 0 0.4445 180)
			(size 0.1397 0.1397)
			(layers "B.Cu" "B.Mask" "B.Paste")
			(net "BMC_SSD_RST#0_A4")
			(options
				(clearance outline)
				(anchor circle)
			)
			(primitives
				(gr_poly
					(pts
						(arc
							(start -0.1778 0.2794)
							(mid -0.249642 0.249642)
							(end -0.2794 0.1778)
						)
						(arc
							(start -0.2794 -0.1778)
							(mid -0.249642 -0.249642)
							(end -0.1778 -0.2794)
						)
						(arc
							(start 0.1778 -0.2794)
							(mid 0.249642 -0.249642)
							(end 0.2794 -0.1778)
						)
						(arc
							(start 0.2794 0.1778)
							(mid 0.249642 0.249642)
							(end 0.1778 0.2794)
						)
					)
					(width 0)
					(fill yes)
				)
			)
		)
	)
	(footprint ""
		(layer "B.Cu")
		(at 50.76952 -126.529846)
		(property "Reference" "TP179"
			(at 0 0 0)
			(layer "B.SilkS")
			(hide yes)
			(effects
				(font
					(size 1.27 1.27)
				)
				(justify mirror)
			)
		)
		(property "Value" "TPAD28-2-GP"
			(at 0.0127 -1.6637 0)
			(unlocked yes)
			(layer "B.Fab")
			(hide yes)
			(effects
				(font
					(size 1.016 1.016)
					(thickness 0.1524)
				)
				(justify mirror)
			)
		)
		(property "Device Type" "TPAD28"
			(at 0.0127 -3.1877 0)
			(unlocked yes)
			(layer "B.Fab")
			(hide yes)
			(effects
				(font
					(size 1.016 1.016)
					(thickness 0.1524)
				)
				(justify mirror)
			)
		)
		(duplicate_pad_numbers_are_jumpers no)
		(fp_poly
			(pts
				(arc
					(start 0.3556 0)
					(mid -0.3556 0)
					(end 0.3556 0)
				)
			)
			(stroke
				(width 0)
				(type default)
			)
			(fill no)
			(layer "B.CrtYd")
		)
		(fp_poly
			(pts
				(arc
					(start 0.6096 0)
					(mid -0.6096 0)
					(end 0.6096 0)
				)
			)
			(stroke
				(width 0)
				(type default)
			)
			(fill no)
			(layer "B.Fab")
		)
		(pad "1" smd circle
			(at 0 0 180)
			(size 0.7112 0.7112)
			(layers "B.Cu" "B.Mask" "B.Paste")
			(net "BMC0_JTAG_RTCK")
		)
	)
)
